(kicad_pcb
	(version 20260206)
	(generator "pcbnew")
	(generator_version "10.0")
	(general
		(thickness 1.6)
		(legacy_teardrops no)
	)
	(paper "A4")
	(title_block
		(title "03242023_DA0F0TMBIJ0_F0T_Motherboard_J_brd_V01_OCP.brd")
		(comment 1 "Grand Teton / footprints 1743-1748 of 6105")
	)
	(layers
		(0 "F.Cu" signal "TOP")
		(4 "In1.Cu" signal "GND")
		(6 "In2.Cu" signal "IN1")
		(8 "In3.Cu" signal "GND1")
		(10 "In4.Cu" signal "IN2")
		(12 "In5.Cu" signal "GND2")
		(14 "In6.Cu" signal "IN3")
		(16 "In7.Cu" signal "GND3")
		(18 "In8.Cu" signal "VCC")
		(20 "In9.Cu" signal "VCC1")
		(22 "In10.Cu" signal "GND4")
		(24 "In11.Cu" signal "IN4")
		(26 "In12.Cu" signal "GND5")
		(28 "In13.Cu" signal "IN5")
		(30 "In14.Cu" signal "GND6")
		(32 "In15.Cu" signal "IN6")
		(34 "In16.Cu" signal "GND7")
		(2 "B.Cu" signal "BOTTOM")
		(9 "F.Adhes" user "F.Adhesive")
		(11 "B.Adhes" user "B.Adhesive")
		(13 "F.Paste" user "Package Geometry/Pastemask Top")
		(15 "B.Paste" user "Package Geometry/Pastemask Bottom")
		(5 "F.SilkS" user "Ref Des/Silkscreen Top")
		(7 "B.SilkS" user "Ref Des/Silkscreen Bottom")
		(1 "F.Mask" user "Board Geometry/Soldermask Top")
		(3 "B.Mask" user "Board Geometry/Soldermask Bottom")
		(17 "Dwgs.User" user "User.Drawings")
		(19 "Cmts.User" user "User.Comments")
		(21 "Eco1.User" user "User.Eco1")
		(23 "Eco2.User" user "User.Eco2")
		(25 "Edge.Cuts" user "Board Geometry/Outline")
		(27 "Margin" user)
		(31 "F.CrtYd" user "Package Geometry/Place Bound Top")
		(29 "B.CrtYd" user "Package Geometry/Place Bound Bottom")
		(35 "F.Fab" user "Ref Des/Assembly Top")
		(33 "B.Fab" user "Ref Des/Assembly Bottom")
	)
	(footprint ""
		(layer "F.Cu")
		(at 191.284606 -126.968758 -90)
		(property "Reference" "R4599"
			(at 0 0 270)
			(layer "F.SilkS")
			(hide yes)
			(effects
				(font
					(size 1.27 1.27)
				)
			)
		)
		(property "Value" ""
			(at 0 0 270)
			(layer "F.Fab")
			(effects
				(font
					(size 1.27 1.27)
				)
			)
		)
		(duplicate_pad_numbers_are_jumpers no)
		(fp_line
			(start -0.7874 0.4064)
			(end -0.7874 -0.4064)
			(stroke
				(width 0.1524)
				(type default)
			)
			(layer "F.SilkS")
		)
		(fp_line
			(start 0.7874 0.4064)
			(end -0.7874 0.4064)
			(stroke
				(width 0.1524)
				(type default)
			)
			(layer "F.SilkS")
		)
		(fp_line
			(start -0.7874 -0.4064)
			(end 0.7874 -0.4064)
			(stroke
				(width 0.1524)
				(type default)
			)
			(layer "F.SilkS")
		)
		(fp_line
			(start 0.7874 -0.4064)
			(end 0.7874 0.4064)
			(stroke
				(width 0.1524)
				(type default)
			)
			(layer "F.SilkS")
		)
		(fp_line
			(start -0.67945 0.3048)
			(end -0.67945 -0.305054)
			(stroke
				(width 0.1)
				(type default)
			)
			(layer "F.Fab")
		)
		(fp_line
			(start -0.12065 0.3048)
			(end -0.67945 0.3048)
			(stroke
				(width 0.1)
				(type default)
			)
			(layer "F.Fab")
		)
		(fp_line
			(start 0.120396 0.3048)
			(end 0.120396 0.2794)
			(stroke
				(width 0.1)
				(type default)
			)
			(layer "F.Fab")
		)
		(fp_line
			(start 0.67945 0.3048)
			(end 0.120396 0.3048)
			(stroke
				(width 0.1)
				(type default)
			)
			(layer "F.Fab")
		)
		(fp_line
			(start -0.12065 0.2794)
			(end -0.12065 0.3048)
			(stroke
				(width 0.1)
				(type default)
			)
			(layer "F.Fab")
		)
		(fp_line
			(start 0.120396 0.2794)
			(end -0.12065 0.2794)
			(stroke
				(width 0.1)
				(type default)
			)
			(layer "F.Fab")
		)
		(fp_line
			(start -0.12065 -0.2794)
			(end 0.12065 -0.2794)
			(stroke
				(width 0.1)
				(type default)
			)
			(layer "F.Fab")
		)
		(fp_line
			(start 0.12065 -0.2794)
			(end 0.12065 -0.3048)
			(stroke
				(width 0.1)
				(type default)
			)
			(layer "F.Fab")
		)
		(fp_line
			(start 0.12065 -0.3048)
			(end 0.67945 -0.3048)
			(stroke
				(width 0.1)
				(type default)
			)
			(layer "F.Fab")
		)
		(fp_line
			(start 0.67945 -0.3048)
			(end 0.67945 0.3048)
			(stroke
				(width 0.1)
				(type default)
			)
			(layer "F.Fab")
		)
		(fp_line
			(start -0.67945 -0.305054)
			(end -0.12065 -0.305054)
			(stroke
				(width 0.1)
				(type default)
			)
			(layer "F.Fab")
		)
		(fp_line
			(start -0.12065 -0.305054)
			(end -0.12065 -0.2794)
			(stroke
				(width 0.1)
				(type default)
			)
			(layer "F.Fab")
		)
		(pad "1" smd circle
			(at -0.40005 0 270)
			(size 0 0)
			(layers "F.Cu" "F.Mask" "F.Paste")
			(net "HP_LVC3_OCP_V3_2_P12V_PWRGD")
		)
		(pad "2" smd circle
			(at 0.40005 0 270)
			(size 0 0)
			(layers "F.Cu" "F.Mask" "F.Paste")
			(net "HP_LVC3_OCP_V3_2_HSC_PWRGD_PLD_")
		)
	)
	(footprint ""
		(layer "F.Cu")
		(at 67.11188 -54.361588)
		(property "Reference" "PR3856"
			(at 0 0 0)
			(layer "F.SilkS")
			(hide yes)
			(effects
				(font
					(size 1.27 1.27)
				)
			)
		)
		(property "Value" ""
			(at 0 0 0)
			(layer "F.Fab")
			(effects
				(font
					(size 1.27 1.27)
				)
			)
		)
		(duplicate_pad_numbers_are_jumpers no)
		(fp_line
			(start -0.7874 -0.4064)
			(end 0.7874 -0.4064)
			(stroke
				(width 0.1524)
				(type default)
			)
			(layer "F.SilkS")
		)
		(fp_line
			(start -0.7874 0.4064)
			(end -0.7874 -0.4064)
			(stroke
				(width 0.1524)
				(type default)
			)
			(layer "F.SilkS")
		)
		(fp_line
			(start 0.7874 -0.4064)
			(end 0.7874 0.4064)
			(stroke
				(width 0.1524)
				(type default)
			)
			(layer "F.SilkS")
		)
		(fp_line
			(start 0.7874 0.4064)
			(end -0.7874 0.4064)
			(stroke
				(width 0.1524)
				(type default)
			)
			(layer "F.SilkS")
		)
		(fp_line
			(start -0.67945 -0.305054)
			(end -0.12065 -0.305054)
			(stroke
				(width 0.1)
				(type default)
			)
			(layer "F.Fab")
		)
		(fp_line
			(start -0.67945 0.3048)
			(end -0.67945 -0.305054)
			(stroke
				(width 0.1)
				(type default)
			)
			(layer "F.Fab")
		)
		(fp_line
			(start -0.12065 -0.305054)
			(end -0.12065 -0.2794)
			(stroke
				(width 0.1)
				(type default)
			)
			(layer "F.Fab")
		)
		(fp_line
			(start -0.12065 -0.2794)
			(end 0.12065 -0.2794)
			(stroke
				(width 0.1)
				(type default)
			)
			(layer "F.Fab")
		)
		(fp_line
			(start -0.12065 0.2794)
			(end -0.12065 0.3048)
			(stroke
				(width 0.1)
				(type default)
			)
			(layer "F.Fab")
		)
		(fp_line
			(start -0.12065 0.3048)
			(end -0.67945 0.3048)
			(stroke
				(width 0.1)
				(type default)
			)
			(layer "F.Fab")
		)
		(fp_line
			(start 0.120396 0.2794)
			(end -0.12065 0.2794)
			(stroke
				(width 0.1)
				(type default)
			)
			(layer "F.Fab")
		)
		(fp_line
			(start 0.120396 0.3048)
			(end 0.120396 0.2794)
			(stroke
				(width 0.1)
				(type default)
			)
			(layer "F.Fab")
		)
		(fp_line
			(start 0.12065 -0.3048)
			(end 0.67945 -0.3048)
			(stroke
				(width 0.1)
				(type default)
			)
			(layer "F.Fab")
		)
		(fp_line
			(start 0.12065 -0.2794)
			(end 0.12065 -0.3048)
			(stroke
				(width 0.1)
				(type default)
			)
			(layer "F.Fab")
		)
		(fp_line
			(start 0.67945 -0.3048)
			(end 0.67945 0.3048)
			(stroke
				(width 0.1)
				(type default)
			)
			(layer "F.Fab")
		)
		(fp_line
			(start 0.67945 0.3048)
			(end 0.120396 0.3048)
			(stroke
				(width 0.1)
				(type default)
			)
			(layer "F.Fab")
		)
		(pad "1" smd circle
			(at -0.40005 0)
			(size 0 0)
			(layers "F.Cu" "F.Mask" "F.Paste")
			(net "GND")
		)
		(pad "2" smd circle
			(at 0.40005 0)
			(size 0 0)
			(layers "F.Cu" "F.Mask" "F.Paste")
			(net "P3V3_OCP_ILIMIT_2")
		)
	)
	(footprint ""
		(layer "F.Cu")
		(at 163.50488 -438.495948 180)
		(property "Reference" "R3449"
			(at 0 0 180)
			(layer "F.SilkS")
			(hide yes)
			(effects
				(font
					(size 1.27 1.27)
				)
			)
		)
		(property "Value" ""
			(at 0 0 180)
			(layer "F.Fab")
			(effects
				(font
					(size 1.27 1.27)
				)
			)
		)
		(duplicate_pad_numbers_are_jumpers no)
		(fp_line
			(start 0.7874 0.4064)
			(end -0.7874 0.4064)
			(stroke
				(width 0.1524)
				(type default)
			)
			(layer "F.SilkS")
		)
		(fp_line
			(start 0.7874 -0.4064)
			(end 0.7874 0.4064)
			(stroke
				(width 0.1524)
				(type default)
			)
			(layer "F.SilkS")
		)
		(fp_line
			(start -0.7874 0.4064)
			(end -0.7874 -0.4064)
			(stroke
				(width 0.1524)
				(type default)
			)
			(layer "F.SilkS")
		)
		(fp_line
			(start -0.7874 -0.4064)
			(end 0.7874 -0.4064)
			(stroke
				(width 0.1524)
				(type default)
			)
			(layer "F.SilkS")
		)
		(fp_line
			(start 0.67945 0.3048)
			(end 0.120396 0.3048)
			(stroke
				(width 0.1)
				(type default)
			)
			(layer "F.Fab")
		)
		(fp_line
			(start 0.67945 -0.3048)
			(end 0.67945 0.3048)
			(stroke
				(width 0.1)
				(type default)
			)
			(layer "F.Fab")
		)
		(fp_line
			(start 0.12065 -0.2794)
			(end 0.12065 -0.3048)
			(stroke
				(width 0.1)
				(type default)
			)
			(layer "F.Fab")
		)
		(fp_line
			(start 0.12065 -0.3048)
			(end 0.67945 -0.3048)
			(stroke
				(width 0.1)
				(type default)
			)
			(layer "F.Fab")
		)
		(fp_line
			(start 0.120396 0.3048)
			(end 0.120396 0.2794)
			(stroke
				(width 0.1)
				(type default)
			)
			(layer "F.Fab")
		)
		(fp_line
			(start 0.120396 0.2794)
			(end -0.12065 0.2794)
			(stroke
				(width 0.1)
				(type default)
			)
			(layer "F.Fab")
		)
		(fp_line
			(start -0.12065 0.3048)
			(end -0.67945 0.3048)
			(stroke
				(width 0.1)
				(type default)
			)
			(layer "F.Fab")
		)
		(fp_line
			(start -0.12065 0.2794)
			(end -0.12065 0.3048)
			(stroke
				(width 0.1)
				(type default)
			)
			(layer "F.Fab")
		)
		(fp_line
			(start -0.12065 -0.2794)
			(end 0.12065 -0.2794)
			(stroke
				(width 0.1)
				(type default)
			)
			(layer "F.Fab")
		)
		(fp_line
			(start -0.12065 -0.305054)
			(end -0.12065 -0.2794)
			(stroke
				(width 0.1)
				(type default)
			)
			(layer "F.Fab")
		)
		(fp_line
			(start -0.67945 0.3048)
			(end -0.67945 -0.305054)
			(stroke
				(width 0.1)
				(type default)
			)
			(layer "F.Fab")
		)
		(fp_line
			(start -0.67945 -0.305054)
			(end -0.12065 -0.305054)
			(stroke
				(width 0.1)
				(type default)
			)
			(layer "F.Fab")
		)
		(pad "1" smd circle
			(at -0.40005 0 180)
			(size 0 0)
			(layers "F.Cu" "F.Mask" "F.Paste")
			(net "GPU_FPGA_BOOT_EN")
		)
		(pad "2" smd circle
			(at 0.40005 0 180)
			(size 0 0)
			(layers "F.Cu" "F.Mask" "F.Paste")
			(net "GND")
		)
	)
	(footprint ""
		(layer "F.Cu")
		(at 20.190714 -107.777026)
		(property "Reference" "R3669"
			(at 0 0 0)
			(layer "F.SilkS")
			(hide yes)
			(effects
				(font
					(size 1.27 1.27)
				)
			)
		)
		(property "Value" ""
			(at 0 0 0)
			(layer "F.Fab")
			(effects
				(font
					(size 1.27 1.27)
				)
			)
		)
		(duplicate_pad_numbers_are_jumpers no)
		(fp_line
			(start -0.7874 -0.4064)
			(end 0.7874 -0.4064)
			(stroke
				(width 0.1524)
				(type default)
			)
			(layer "F.SilkS")
		)
		(fp_line
			(start -0.7874 0.4064)
			(end -0.7874 -0.4064)
			(stroke
				(width 0.1524)
				(type default)
			)
			(layer "F.SilkS")
		)
		(fp_line
			(start 0.7874 -0.4064)
			(end 0.7874 0.4064)
			(stroke
				(width 0.1524)
				(type default)
			)
			(layer "F.SilkS")
		)
		(fp_line
			(start 0.7874 0.4064)
			(end -0.7874 0.4064)
			(stroke
				(width 0.1524)
				(type default)
			)
			(layer "F.SilkS")
		)
		(fp_line
			(start -0.67945 -0.305054)
			(end -0.12065 -0.305054)
			(stroke
				(width 0.1)
				(type default)
			)
			(layer "F.Fab")
		)
		(fp_line
			(start -0.67945 0.3048)
			(end -0.67945 -0.305054)
			(stroke
				(width 0.1)
				(type default)
			)
			(layer "F.Fab")
		)
		(fp_line
			(start -0.12065 -0.305054)
			(end -0.12065 -0.2794)
			(stroke
				(width 0.1)
				(type default)
			)
			(layer "F.Fab")
		)
		(fp_line
			(start -0.12065 -0.2794)
			(end 0.12065 -0.2794)
			(stroke
				(width 0.1)
				(type default)
			)
			(layer "F.Fab")
		)
		(fp_line
			(start -0.12065 0.2794)
			(end -0.12065 0.3048)
			(stroke
				(width 0.1)
				(type default)
			)
			(layer "F.Fab")
		)
		(fp_line
			(start -0.12065 0.3048)
			(end -0.67945 0.3048)
			(stroke
				(width 0.1)
				(type default)
			)
			(layer "F.Fab")
		)
		(fp_line
			(start 0.120396 0.2794)
			(end -0.12065 0.2794)
			(stroke
				(width 0.1)
				(type default)
			)
			(layer "F.Fab")
		)
		(fp_line
			(start 0.120396 0.3048)
			(end 0.120396 0.2794)
			(stroke
				(width 0.1)
				(type default)
			)
			(layer "F.Fab")
		)
		(fp_line
			(start 0.12065 -0.3048)
			(end 0.67945 -0.3048)
			(stroke
				(width 0.1)
				(type default)
			)
			(layer "F.Fab")
		)
		(fp_line
			(start 0.12065 -0.2794)
			(end 0.12065 -0.3048)
			(stroke
				(width 0.1)
				(type default)
			)
			(layer "F.Fab")
		)
		(fp_line
			(start 0.67945 -0.3048)
			(end 0.67945 0.3048)
			(stroke
				(width 0.1)
				(type default)
			)
			(layer "F.Fab")
		)
		(fp_line
			(start 0.67945 0.3048)
			(end 0.120396 0.3048)
			(stroke
				(width 0.1)
				(type default)
			)
			(layer "F.Fab")
		)
		(pad "1" smd circle
			(at -0.40005 0)
			(size 0 0)
			(layers "F.Cu" "F.Mask" "F.Paste")
			(net "P3V3_AUX")
		)
		(pad "2" smd circle
			(at 0.40005 0)
			(size 0 0)
			(layers "F.Cu" "F.Mask" "F.Paste")
			(net "ADC128_A0")
		)
	)
	(footprint ""
		(layer "F.Cu")
		(at 257.85953 -54.463442)
		(property "Reference" "PR3949"
			(at 0 0 0)
			(layer "F.SilkS")
			(hide yes)
			(effects
				(font
					(size 1.27 1.27)
				)
			)
		)
		(property "Value" ""
			(at 0 0 0)
			(layer "F.Fab")
			(effects
				(font
					(size 1.27 1.27)
				)
			)
		)
		(duplicate_pad_numbers_are_jumpers no)
		(fp_line
			(start -0.7874 -0.4064)
			(end 0.7874 -0.4064)
			(stroke
				(width 0.1524)
				(type default)
			)
			(layer "F.SilkS")
		)
		(fp_line
			(start -0.7874 0.4064)
			(end -0.7874 -0.4064)
			(stroke
				(width 0.1524)
				(type default)
			)
			(layer "F.SilkS")
		)
		(fp_line
			(start 0.7874 -0.4064)
			(end 0.7874 0.4064)
			(stroke
				(width 0.1524)
				(type default)
			)
			(layer "F.SilkS")
		)
		(fp_line
			(start 0.7874 0.4064)
			(end -0.7874 0.4064)
			(stroke
				(width 0.1524)
				(type default)
			)
			(layer "F.SilkS")
		)
		(fp_line
			(start -0.67945 -0.305054)
			(end -0.12065 -0.305054)
			(stroke
				(width 0.1)
				(type default)
			)
			(layer "F.Fab")
		)
		(fp_line
			(start -0.67945 0.3048)
			(end -0.67945 -0.305054)
			(stroke
				(width 0.1)
				(type default)
			)
			(layer "F.Fab")
		)
		(fp_line
			(start -0.12065 -0.305054)
			(end -0.12065 -0.2794)
			(stroke
				(width 0.1)
				(type default)
			)
			(layer "F.Fab")
		)
		(fp_line
			(start -0.12065 -0.2794)
			(end 0.12065 -0.2794)
			(stroke
				(width 0.1)
				(type default)
			)
			(layer "F.Fab")
		)
		(fp_line
			(start -0.12065 0.2794)
			(end -0.12065 0.3048)
			(stroke
				(width 0.1)
				(type default)
			)
			(layer "F.Fab")
		)
		(fp_line
			(start -0.12065 0.3048)
			(end -0.67945 0.3048)
			(stroke
				(width 0.1)
				(type default)
			)
			(layer "F.Fab")
		)
		(fp_line
			(start 0.120396 0.2794)
			(end -0.12065 0.2794)
			(stroke
				(width 0.1)
				(type default)
			)
			(layer "F.Fab")
		)
		(fp_line
			(start 0.120396 0.3048)
			(end 0.120396 0.2794)
			(stroke
				(width 0.1)
				(type default)
			)
			(layer "F.Fab")
		)
		(fp_line
			(start 0.12065 -0.3048)
			(end 0.67945 -0.3048)
			(stroke
				(width 0.1)
				(type default)
			)
			(layer "F.Fab")
		)
		(fp_line
			(start 0.12065 -0.2794)
			(end 0.12065 -0.3048)
			(stroke
				(width 0.1)
				(type default)
			)
			(layer "F.Fab")
		)
		(fp_line
			(start 0.67945 -0.3048)
			(end 0.67945 0.3048)
			(stroke
				(width 0.1)
				(type default)
			)
			(layer "F.Fab")
		)
		(fp_line
			(start 0.67945 0.3048)
			(end 0.120396 0.3048)
			(stroke
				(width 0.1)
				(type default)
			)
			(layer "F.Fab")
		)
		(pad "1" smd circle
			(at -0.40005 0)
			(size 0 0)
			(layers "F.Cu" "F.Mask" "F.Paste")
			(net "P12V_E1S_IMON_0")
		)
		(pad "2" smd circle
			(at 0.40005 0)
			(size 0 0)
			(layers "F.Cu" "F.Mask" "F.Paste")
			(net "GND")
		)
	)
	(footprint ""
		(layer "F.Cu")
		(at 193.93408 -352.694748)
		(property "Reference" "R626"
			(at 0 0 0)
			(layer "F.SilkS")
			(hide yes)
			(effects
				(font
					(size 1.27 1.27)
				)
			)
		)
		(property "Value" ""
			(at 0 0 0)
			(layer "F.Fab")
			(effects
				(font
					(size 1.27 1.27)
				)
			)
		)
		(duplicate_pad_numbers_are_jumpers no)
		(fp_line
			(start -0.7874 -0.4064)
			(end 0.7874 -0.4064)
			(stroke
				(width 0.1524)
				(type default)
			)
			(layer "F.SilkS")
		)
		(fp_line
			(start -0.7874 0.4064)
			(end -0.7874 -0.4064)
			(stroke
				(width 0.1524)
				(type default)
			)
			(layer "F.SilkS")
		)
		(fp_line
			(start 0.7874 -0.4064)
			(end 0.7874 0.4064)
			(stroke
				(width 0.1524)
				(type default)
			)
			(layer "F.SilkS")
		)
		(fp_line
			(start 0.7874 0.4064)
			(end -0.7874 0.4064)
			(stroke
				(width 0.1524)
				(type default)
			)
			(layer "F.SilkS")
		)
		(fp_line
			(start -0.67945 -0.305054)
			(end -0.12065 -0.305054)
			(stroke
				(width 0.1)
				(type default)
			)
			(layer "F.Fab")
		)
		(fp_line
			(start -0.67945 0.3048)
			(end -0.67945 -0.305054)
			(stroke
				(width 0.1)
				(type default)
			)
			(layer "F.Fab")
		)
		(fp_line
			(start -0.12065 -0.305054)
			(end -0.12065 -0.2794)
			(stroke
				(width 0.1)
				(type default)
			)
			(layer "F.Fab")
		)
		(fp_line
			(start -0.12065 -0.2794)
			(end 0.12065 -0.2794)
			(stroke
				(width 0.1)
				(type default)
			)
			(layer "F.Fab")
		)
		(fp_line
			(start -0.12065 0.2794)
			(end -0.12065 0.3048)
			(stroke
				(width 0.1)
				(type default)
			)
			(layer "F.Fab")
		)
		(fp_line
			(start -0.12065 0.3048)
			(end -0.67945 0.3048)
			(stroke
				(width 0.1)
				(type default)
			)
			(layer "F.Fab")
		)
		(fp_line
			(start 0.120396 0.2794)
			(end -0.12065 0.2794)
			(stroke
				(width 0.1)
				(type default)
			)
			(layer "F.Fab")
		)
		(fp_line
			(start 0.120396 0.3048)
			(end 0.120396 0.2794)
			(stroke
				(width 0.1)
				(type default)
			)
			(layer "F.Fab")
		)
		(fp_line
			(start 0.12065 -0.3048)
			(end 0.67945 -0.3048)
			(stroke
				(width 0.1)
				(type default)
			)
			(layer "F.Fab")
		)
		(fp_line
			(start 0.12065 -0.2794)
			(end 0.12065 -0.3048)
			(stroke
				(width 0.1)
				(type default)
			)
			(layer "F.Fab")
		)
		(fp_line
			(start 0.67945 -0.3048)
			(end 0.67945 0.3048)
			(stroke
				(width 0.1)
				(type default)
			)
			(layer "F.Fab")
		)
		(fp_line
			(start 0.67945 0.3048)
			(end 0.120396 0.3048)
			(stroke
				(width 0.1)
				(type default)
			)
			(layer "F.Fab")
		)
		(pad "1" smd circle
			(at -0.40005 0)
			(size 0 0)
			(layers "F.Cu" "F.Mask" "F.Paste")
			(net "PD_PIROM_CPU1_ADDR2")
		)
		(pad "2" smd circle
			(at 0.40005 0)
			(size 0 0)
			(layers "F.Cu" "F.Mask" "F.Paste")
			(net "GND")
		)
	)
)
